(kicad_pcb
	(version 20260206)
	(generator "pcbnew")
	(generator_version "10.0")
	(general
		(thickness 1.6)
		(legacy_teardrops no)
	)
	(paper "A4")
	(title_block
		(title "Wiwynn_Tioga_Pass_MB.brd")
		(comment 1 "Tioga Pass / footprint 2141 of 4770 (J1G2), pads 124-243 of 291")
	)
	(layers
		(0 "F.Cu" signal "TOP")
		(4 "In1.Cu" signal "L2GND")
		(6 "In2.Cu" signal "L3")
		(8 "In3.Cu" signal "L4GND")
		(10 "In4.Cu" signal "L5")
		(12 "In5.Cu" signal "L6GND")
		(14 "In6.Cu" signal "L7VCC")
		(16 "In7.Cu" signal "L8VCC")
		(18 "In8.Cu" signal "L9GND")
		(20 "In9.Cu" signal "L10")
		(22 "In10.Cu" signal "L11GND")
		(24 "In11.Cu" signal "L12")
		(26 "In12.Cu" signal "L13GND")
		(2 "B.Cu" signal "BOTTOM")
		(9 "F.Adhes" user "F.Adhesive")
		(11 "B.Adhes" user "B.Adhesive")
		(13 "F.Paste" user "Package Geometry/Pastemask Top")
		(15 "B.Paste" user "Package Geometry/Pastemask Bottom")
		(5 "F.SilkS" user "Ref Des/Silkscreen Top")
		(7 "B.SilkS" user "Ref Des/Silkscreen Bottom")
		(1 "F.Mask" user "Board Geometry/Soldermask Top")
		(3 "B.Mask" user "Board Geometry/Soldermask Bottom")
		(17 "Dwgs.User" user "User.Drawings")
		(19 "Cmts.User" user "User.Comments")
		(21 "Eco1.User" user "User.Eco1")
		(23 "Eco2.User" user "User.Eco2")
		(25 "Edge.Cuts" user "Board Geometry/Outline")
		(27 "Margin" user)
		(31 "F.CrtYd" user "Package Geometry/Place Bound Top")
		(29 "B.CrtYd" user "Package Geometry/Place Bound Bottom")
		(35 "F.Fab" user "Ref Des/Assembly Top")
		(33 "B.Fab" user "Ref Des/Assembly Bottom")
	)
	(footprint ""
		(layer "F.Cu")
		(at 29.699458 -5.822442 90)
		(property "Reference" "J1G2"
			(at 7.104888 34.562542 0)
			(unlocked yes)
			(layer "F.SilkS")
			(effects
				(font
					(size 0.7874 0.5842)
					(thickness 0.1524)
				)
				(justify left)
			)
		)
		(property "Value" ""
			(at 0 0 90)
			(layer "F.Fab")
			(effects
				(font
					(size 1.27 1.27)
				)
			)
		)
		(duplicate_pad_numbers_are_jumpers no)
		(pad "121" smd rect
			(at 0 107.100116 90)
			(size 1.8034 0.508)
			(layers "F.Cu" "F.Mask" "F.Paste")
			(net "M_H_DQS_DP<15>")
		)
		(pad "122" smd rect
			(at 0 107.95 90)
			(size 1.8034 0.508)
			(layers "F.Cu" "F.Mask" "F.Paste")
			(net "M_H_DQS_DN<15>")
		)
		(pad "123" smd rect
			(at 0 108.799884 90)
			(size 1.8034 0.508)
			(layers "F.Cu" "F.Mask" "F.Paste")
			(net "GND")
		)
		(pad "124" smd rect
			(at 0 109.650022 90)
			(size 1.8034 0.508)
			(layers "F.Cu" "F.Mask" "F.Paste")
			(net "M_H_DQ<55>")
		)
		(pad "125" smd rect
			(at 0 110.499906 90)
			(size 1.8034 0.508)
			(layers "F.Cu" "F.Mask" "F.Paste")
			(net "GND")
		)
		(pad "126" smd rect
			(at 0 111.350044 90)
			(size 1.8034 0.508)
			(layers "F.Cu" "F.Mask" "F.Paste")
			(net "M_H_DQ<51>")
		)
		(pad "127" smd rect
			(at 0 112.199928 90)
			(size 1.8034 0.508)
			(layers "F.Cu" "F.Mask" "F.Paste")
			(net "GND")
		)
		(pad "128" smd rect
			(at 0 113.050066 90)
			(size 1.8034 0.508)
			(layers "F.Cu" "F.Mask" "F.Paste")
			(net "M_H_DQ<61>")
		)
		(pad "129" smd rect
			(at 0 113.89995 90)
			(size 1.8034 0.508)
			(layers "F.Cu" "F.Mask" "F.Paste")
			(net "GND")
		)
		(pad "130" smd rect
			(at 0 114.750088 90)
			(size 1.8034 0.508)
			(layers "F.Cu" "F.Mask" "F.Paste")
			(net "M_H_DQ<57>")
		)
		(pad "131" smd rect
			(at 0 115.599972 90)
			(size 1.8034 0.508)
			(layers "F.Cu" "F.Mask" "F.Paste")
			(net "GND")
		)
		(pad "132" smd rect
			(at 0 116.45011 90)
			(size 1.8034 0.508)
			(layers "F.Cu" "F.Mask" "F.Paste")
			(net "M_H_DQS_DP<16>")
		)
		(pad "133" smd rect
			(at 0 117.299994 90)
			(size 1.8034 0.508)
			(layers "F.Cu" "F.Mask" "F.Paste")
			(net "M_H_DQS_DN<16>")
		)
		(pad "134" smd rect
			(at 0 118.149878 90)
			(size 1.8034 0.508)
			(layers "F.Cu" "F.Mask" "F.Paste")
			(net "GND")
		)
		(pad "135" smd rect
			(at 0 119.000016 90)
			(size 1.8034 0.508)
			(layers "F.Cu" "F.Mask" "F.Paste")
			(net "M_H_DQ<63>")
		)
		(pad "136" smd rect
			(at 0 119.8499 90)
			(size 1.8034 0.508)
			(layers "F.Cu" "F.Mask" "F.Paste")
			(net "GND")
		)
		(pad "137" smd rect
			(at 0 120.700038 90)
			(size 1.8034 0.508)
			(layers "F.Cu" "F.Mask" "F.Paste")
			(net "M_H_DQ<59>")
		)
		(pad "138" smd rect
			(at 0 121.549922 90)
			(size 1.8034 0.508)
			(layers "F.Cu" "F.Mask" "F.Paste")
			(net "GND")
		)
		(pad "139" smd rect
			(at 0 122.40006 90)
			(size 1.8034 0.508)
			(layers "F.Cu" "F.Mask" "F.Paste")
			(net "GND")
		)
		(pad "140" smd rect
			(at 0 123.249944 90)
			(size 1.8034 0.508)
			(layers "F.Cu" "F.Mask" "F.Paste")
			(net "PVPP_GHJ")
		)
		(pad "141" smd rect
			(at 0 124.100082 90)
			(size 1.8034 0.508)
			(layers "F.Cu" "F.Mask" "F.Paste")
			(net "SMB_DDR_GHJ_VPP_SCL")
		)
		(pad "142" smd rect
			(at 0 124.949966 90)
			(size 1.8034 0.508)
			(layers "F.Cu" "F.Mask" "F.Paste")
			(net "PVPP_GHJ")
		)
		(pad "143" smd rect
			(at 0 125.800104 90)
			(size 1.8034 0.508)
			(layers "F.Cu" "F.Mask" "F.Paste")
			(net "PVPP_GHJ")
		)
		(pad "144" smd rect
			(at 0 126.649988 90)
			(size 1.8034 0.508)
			(layers "F.Cu" "F.Mask" "F.Paste")
			(net "TP_CH_H_DIMM_H0_RFU_2")
		)
		(pad "145" smd rect
			(at 4.59994 0 90)
			(size 1.8034 0.508)
			(layers "F.Cu" "F.Mask" "F.Paste")
			(net "P12V_NVDIMM_GHJ")
		)
		(pad "146" smd rect
			(at 4.59994 0.849884 90)
			(size 1.8034 0.508)
			(layers "F.Cu" "F.Mask" "F.Paste")
			(net "M_H_VREF")
		)
		(pad "147" smd rect
			(at 4.59994 1.700022 90)
			(size 1.8034 0.508)
			(layers "F.Cu" "F.Mask" "F.Paste")
			(net "GND")
		)
		(pad "148" smd rect
			(at 4.59994 2.549906 90)
			(size 1.8034 0.508)
			(layers "F.Cu" "F.Mask" "F.Paste")
			(net "M_H_DQ<4>")
		)
		(pad "149" smd rect
			(at 4.59994 3.400044 90)
			(size 1.8034 0.508)
			(layers "F.Cu" "F.Mask" "F.Paste")
			(net "GND")
		)
		(pad "150" smd rect
			(at 4.59994 4.249928 90)
			(size 1.8034 0.508)
			(layers "F.Cu" "F.Mask" "F.Paste")
			(net "M_H_DQ<0>")
		)
		(pad "151" smd rect
			(at 4.59994 5.100066 90)
			(size 1.8034 0.508)
			(layers "F.Cu" "F.Mask" "F.Paste")
			(net "GND")
		)
		(pad "152" smd rect
			(at 4.59994 5.94995 90)
			(size 1.8034 0.508)
			(layers "F.Cu" "F.Mask" "F.Paste")
			(net "M_H_DQS_DN<0>")
		)
		(pad "153" smd rect
			(at 4.59994 6.800088 90)
			(size 1.8034 0.508)
			(layers "F.Cu" "F.Mask" "F.Paste")
			(net "M_H_DQS_DP<0>")
		)
		(pad "154" smd rect
			(at 4.59994 7.649972 90)
			(size 1.8034 0.508)
			(layers "F.Cu" "F.Mask" "F.Paste")
			(net "GND")
		)
		(pad "155" smd rect
			(at 4.59994 8.50011 90)
			(size 1.8034 0.508)
			(layers "F.Cu" "F.Mask" "F.Paste")
			(net "M_H_DQ<6>")
		)
		(pad "156" smd rect
			(at 4.59994 9.349994 90)
			(size 1.8034 0.508)
			(layers "F.Cu" "F.Mask" "F.Paste")
			(net "GND")
		)
		(pad "157" smd rect
			(at 4.59994 10.199878 90)
			(size 1.8034 0.508)
			(layers "F.Cu" "F.Mask" "F.Paste")
			(net "M_H_DQ<2>")
		)
		(pad "158" smd rect
			(at 4.59994 11.050016 90)
			(size 1.8034 0.508)
			(layers "F.Cu" "F.Mask" "F.Paste")
			(net "GND")
		)
		(pad "159" smd rect
			(at 4.59994 11.8999 90)
			(size 1.8034 0.508)
			(layers "F.Cu" "F.Mask" "F.Paste")
			(net "M_H_DQ<12>")
		)
		(pad "160" smd rect
			(at 4.59994 12.750038 90)
			(size 1.8034 0.508)
			(layers "F.Cu" "F.Mask" "F.Paste")
			(net "GND")
		)
		(pad "161" smd rect
			(at 4.59994 13.599922 90)
			(size 1.8034 0.508)
			(layers "F.Cu" "F.Mask" "F.Paste")
			(net "M_H_DQ<8>")
		)
		(pad "162" smd rect
			(at 4.59994 14.45006 90)
			(size 1.8034 0.508)
			(layers "F.Cu" "F.Mask" "F.Paste")
			(net "GND")
		)
		(pad "163" smd rect
			(at 4.59994 15.299944 90)
			(size 1.8034 0.508)
			(layers "F.Cu" "F.Mask" "F.Paste")
			(net "M_H_DQS_DN<1>")
		)
		(pad "164" smd rect
			(at 4.59994 16.150082 90)
			(size 1.8034 0.508)
			(layers "F.Cu" "F.Mask" "F.Paste")
			(net "M_H_DQS_DP<1>")
		)
		(pad "165" smd rect
			(at 4.59994 16.999966 90)
			(size 1.8034 0.508)
			(layers "F.Cu" "F.Mask" "F.Paste")
			(net "GND")
		)
		(pad "166" smd rect
			(at 4.59994 17.850104 90)
			(size 1.8034 0.508)
			(layers "F.Cu" "F.Mask" "F.Paste")
			(net "M_H_DQ<14>")
		)
		(pad "167" smd rect
			(at 4.59994 18.699988 90)
			(size 1.8034 0.508)
			(layers "F.Cu" "F.Mask" "F.Paste")
			(net "GND")
		)
		(pad "168" smd rect
			(at 4.59994 19.550126 90)
			(size 1.8034 0.508)
			(layers "F.Cu" "F.Mask" "F.Paste")
			(net "M_H_DQ<10>")
		)
		(pad "169" smd rect
			(at 4.59994 20.40001 90)
			(size 1.8034 0.508)
			(layers "F.Cu" "F.Mask" "F.Paste")
			(net "GND")
		)
		(pad "170" smd rect
			(at 4.59994 21.249894 90)
			(size 1.8034 0.508)
			(layers "F.Cu" "F.Mask" "F.Paste")
			(net "M_H_DQ<20>")
		)
		(pad "171" smd rect
			(at 4.59994 22.100032 90)
			(size 1.8034 0.508)
			(layers "F.Cu" "F.Mask" "F.Paste")
			(net "GND")
		)
		(pad "172" smd rect
			(at 4.59994 22.949916 90)
			(size 1.8034 0.508)
			(layers "F.Cu" "F.Mask" "F.Paste")
			(net "M_H_DQ<16>")
		)
		(pad "173" smd rect
			(at 4.59994 23.800054 90)
			(size 1.8034 0.508)
			(layers "F.Cu" "F.Mask" "F.Paste")
			(net "GND")
		)
		(pad "174" smd rect
			(at 4.59994 24.649938 90)
			(size 1.8034 0.508)
			(layers "F.Cu" "F.Mask" "F.Paste")
			(net "M_H_DQS_DN<2>")
		)
		(pad "175" smd rect
			(at 4.59994 25.500076 90)
			(size 1.8034 0.508)
			(layers "F.Cu" "F.Mask" "F.Paste")
			(net "M_H_DQS_DP<2>")
		)
		(pad "176" smd rect
			(at 4.59994 26.34996 90)
			(size 1.8034 0.508)
			(layers "F.Cu" "F.Mask" "F.Paste")
			(net "GND")
		)
		(pad "177" smd rect
			(at 4.59994 27.200098 90)
			(size 1.8034 0.508)
			(layers "F.Cu" "F.Mask" "F.Paste")
			(net "M_H_DQ<22>")
		)
		(pad "178" smd rect
			(at 4.59994 28.049982 90)
			(size 1.8034 0.508)
			(layers "F.Cu" "F.Mask" "F.Paste")
			(net "GND")
		)
		(pad "179" smd rect
			(at 4.59994 28.90012 90)
			(size 1.8034 0.508)
			(layers "F.Cu" "F.Mask" "F.Paste")
			(net "M_H_DQ<18>")
		)
		(pad "180" smd rect
			(at 4.59994 29.750004 90)
			(size 1.8034 0.508)
			(layers "F.Cu" "F.Mask" "F.Paste")
			(net "GND")
		)
		(pad "181" smd rect
			(at 4.59994 30.599888 90)
			(size 1.8034 0.508)
			(layers "F.Cu" "F.Mask" "F.Paste")
			(net "M_H_DQ<28>")
		)
		(pad "182" smd rect
			(at 4.59994 31.450026 90)
			(size 1.8034 0.508)
			(layers "F.Cu" "F.Mask" "F.Paste")
			(net "GND")
		)
		(pad "183" smd rect
			(at 4.59994 32.29991 90)
			(size 1.8034 0.508)
			(layers "F.Cu" "F.Mask" "F.Paste")
			(net "M_H_DQ<24>")
		)
		(pad "184" smd rect
			(at 4.59994 33.150048 90)
			(size 1.8034 0.508)
			(layers "F.Cu" "F.Mask" "F.Paste")
			(net "GND")
		)
		(pad "185" smd rect
			(at 4.59994 33.999932 90)
			(size 1.8034 0.508)
			(layers "F.Cu" "F.Mask" "F.Paste")
			(net "M_H_DQS_DN<3>")
		)
		(pad "186" smd rect
			(at 4.59994 34.85007 90)
			(size 1.8034 0.508)
			(layers "F.Cu" "F.Mask" "F.Paste")
			(net "M_H_DQS_DP<3>")
		)
		(pad "187" smd rect
			(at 4.59994 35.699954 90)
			(size 1.8034 0.508)
			(layers "F.Cu" "F.Mask" "F.Paste")
			(net "GND")
		)
		(pad "188" smd rect
			(at 4.59994 36.550092 90)
			(size 1.8034 0.508)
			(layers "F.Cu" "F.Mask" "F.Paste")
			(net "M_H_DQ<30>")
		)
		(pad "189" smd rect
			(at 4.59994 37.399976 90)
			(size 1.8034 0.508)
			(layers "F.Cu" "F.Mask" "F.Paste")
			(net "GND")
		)
		(pad "190" smd rect
			(at 4.59994 38.250114 90)
			(size 1.8034 0.508)
			(layers "F.Cu" "F.Mask" "F.Paste")
			(net "M_H_DQ<26>")
		)
		(pad "191" smd rect
			(at 4.59994 39.099998 90)
			(size 1.8034 0.508)
			(layers "F.Cu" "F.Mask" "F.Paste")
			(net "GND")
		)
		(pad "192" smd rect
			(at 4.59994 39.949882 90)
			(size 1.8034 0.508)
			(layers "F.Cu" "F.Mask" "F.Paste")
			(net "M_H_ECC<4>")
		)
		(pad "193" smd rect
			(at 4.59994 40.80002 90)
			(size 1.8034 0.508)
			(layers "F.Cu" "F.Mask" "F.Paste")
			(net "GND")
		)
		(pad "194" smd rect
			(at 4.59994 41.649904 90)
			(size 1.8034 0.508)
			(layers "F.Cu" "F.Mask" "F.Paste")
			(net "M_H_ECC<0>")
		)
		(pad "195" smd rect
			(at 4.59994 42.500042 90)
			(size 1.8034 0.508)
			(layers "F.Cu" "F.Mask" "F.Paste")
			(net "GND")
		)
		(pad "196" smd rect
			(at 4.59994 43.349926 90)
			(size 1.8034 0.508)
			(layers "F.Cu" "F.Mask" "F.Paste")
			(net "M_H_DQS_DN<8>")
		)
		(pad "197" smd rect
			(at 4.59994 44.200064 90)
			(size 1.8034 0.508)
			(layers "F.Cu" "F.Mask" "F.Paste")
			(net "M_H_DQS_DP<8>")
		)
		(pad "198" smd rect
			(at 4.59994 45.049948 90)
			(size 1.8034 0.508)
			(layers "F.Cu" "F.Mask" "F.Paste")
			(net "GND")
		)
		(pad "199" smd rect
			(at 4.59994 45.900086 90)
			(size 1.8034 0.508)
			(layers "F.Cu" "F.Mask" "F.Paste")
			(net "M_H_ECC<6>")
		)
		(pad "200" smd rect
			(at 4.59994 46.74997 90)
			(size 1.8034 0.508)
			(layers "F.Cu" "F.Mask" "F.Paste")
			(net "GND")
		)
		(pad "201" smd rect
			(at 4.59994 47.600108 90)
			(size 1.8034 0.508)
			(layers "F.Cu" "F.Mask" "F.Paste")
			(net "M_H_ECC<2>")
		)
		(pad "202" smd rect
			(at 4.59994 48.449992 90)
			(size 1.8034 0.508)
			(layers "F.Cu" "F.Mask" "F.Paste")
			(net "GND")
		)
		(pad "203" smd rect
			(at 4.59994 49.299876 90)
			(size 1.8034 0.508)
			(layers "F.Cu" "F.Mask" "F.Paste")
			(net "M_H_CKE<1>")
		)
		(pad "204" smd rect
			(at 4.59994 50.150014 90)
			(size 1.8034 0.508)
			(layers "F.Cu" "F.Mask" "F.Paste")
			(net "PVDDQ_GHJ")
		)
		(pad "205" smd rect
			(at 4.59994 50.999898 90)
			(size 1.8034 0.508)
			(layers "F.Cu" "F.Mask" "F.Paste")
			(net "TP_CH_H_DIMM_H0_RFU_0")
		)
		(pad "206" smd rect
			(at 4.59994 51.850036 90)
			(size 1.8034 0.508)
			(layers "F.Cu" "F.Mask" "F.Paste")
			(net "PVDDQ_GHJ")
		)
		(pad "207" smd rect
			(at 4.59994 52.69992 90)
			(size 1.8034 0.508)
			(layers "F.Cu" "F.Mask" "F.Paste")
			(net "M_H_BG<1>")
		)
		(pad "208" smd rect
			(at 4.59994 53.550058 90)
			(size 1.8034 0.508)
			(layers "F.Cu" "F.Mask" "F.Paste")
			(net "M_H_ALERT_N")
		)
		(pad "209" smd rect
			(at 4.59994 54.399942 90)
			(size 1.8034 0.508)
			(layers "F.Cu" "F.Mask" "F.Paste")
			(net "PVDDQ_GHJ")
		)
		(pad "210" smd rect
			(at 4.59994 55.25008 90)
			(size 1.8034 0.508)
			(layers "F.Cu" "F.Mask" "F.Paste")
			(net "M_H_MA<11>")
		)
		(pad "211" smd rect
			(at 4.59994 56.099964 90)
			(size 1.8034 0.508)
			(layers "F.Cu" "F.Mask" "F.Paste")
			(net "M_H_MA<7>")
		)
		(pad "212" smd rect
			(at 4.59994 56.950102 90)
			(size 1.8034 0.508)
			(layers "F.Cu" "F.Mask" "F.Paste")
			(net "PVDDQ_GHJ")
		)
		(pad "213" smd rect
			(at 4.59994 57.799986 90)
			(size 1.8034 0.508)
			(layers "F.Cu" "F.Mask" "F.Paste")
			(net "M_H_MA<5>")
		)
		(pad "214" smd rect
			(at 4.59994 58.650124 90)
			(size 1.8034 0.508)
			(layers "F.Cu" "F.Mask" "F.Paste")
			(net "M_H_MA<4>")
		)
		(pad "215" smd rect
			(at 4.59994 59.500008 90)
			(size 1.8034 0.508)
			(layers "F.Cu" "F.Mask" "F.Paste")
			(net "PVDDQ_GHJ")
		)
		(pad "216" smd rect
			(at 4.59994 60.349892 90)
			(size 1.8034 0.508)
			(layers "F.Cu" "F.Mask" "F.Paste")
			(net "M_H_MA<2>")
		)
		(pad "217" smd rect
			(at 4.59994 61.20003 90)
			(size 1.8034 0.508)
			(layers "F.Cu" "F.Mask" "F.Paste")
			(net "PVDDQ_GHJ")
		)
		(pad "218" smd rect
			(at 4.59994 62.049914 90)
			(size 1.8034 0.508)
			(layers "F.Cu" "F.Mask" "F.Paste")
			(net "M_H_CLK_DP<1>")
		)
		(pad "219" smd rect
			(at 4.59994 62.900052 90)
			(size 1.8034 0.508)
			(layers "F.Cu" "F.Mask" "F.Paste")
			(net "M_H_CLK_DN<1>")
		)
		(pad "220" smd rect
			(at 4.59994 63.749936 90)
			(size 1.8034 0.508)
			(layers "F.Cu" "F.Mask" "F.Paste")
			(net "PVDDQ_GHJ")
		)
		(pad "221" smd rect
			(at 4.59994 64.600074 90)
			(size 1.8034 0.508)
			(layers "F.Cu" "F.Mask" "F.Paste")
			(net "PVTT_GHJ")
		)
		(pad "222" smd rect
			(at 4.59994 70.550024 90)
			(size 1.8034 0.508)
			(layers "F.Cu" "F.Mask" "F.Paste")
			(net "M_H_PAR")
		)
		(pad "223" smd rect
			(at 4.59994 71.399908 90)
			(size 1.8034 0.508)
			(layers "F.Cu" "F.Mask" "F.Paste")
			(net "PVDDQ_GHJ")
		)
		(pad "224" smd rect
			(at 4.59994 72.250046 90)
			(size 1.8034 0.508)
			(layers "F.Cu" "F.Mask" "F.Paste")
			(net "M_H_BA<1>")
		)
		(pad "225" smd rect
			(at 4.59994 73.09993 90)
			(size 1.8034 0.508)
			(layers "F.Cu" "F.Mask" "F.Paste")
			(net "M_H_MA<10>")
		)
		(pad "226" smd rect
			(at 4.59994 73.950068 90)
			(size 1.8034 0.508)
			(layers "F.Cu" "F.Mask" "F.Paste")
			(net "PVDDQ_GHJ")
		)
		(pad "227" smd rect
			(at 4.59994 74.799952 90)
			(size 1.8034 0.508)
			(layers "F.Cu" "F.Mask" "F.Paste")
			(net "TP_CH_H_DIMM_H0_RFU_1")
		)
		(pad "228" smd rect
			(at 4.59994 75.65009 90)
			(size 1.8034 0.508)
			(layers "F.Cu" "F.Mask" "F.Paste")
			(net "M_H_MA<14>")
		)
		(pad "229" smd rect
			(at 4.59994 76.499974 90)
			(size 1.8034 0.508)
			(layers "F.Cu" "F.Mask" "F.Paste")
			(net "PVDDQ_GHJ")
		)
		(pad "230" smd rect
			(at 4.59994 77.350112 90)
			(size 1.8034 0.508)
			(layers "F.Cu" "F.Mask" "F.Paste")
			(net "FM_ADR_COMPLETE_GHJ_N")
		)
		(pad "231" smd rect
			(at 4.59994 78.199996 90)
			(size 1.8034 0.508)
			(layers "F.Cu" "F.Mask" "F.Paste")
			(net "PVDDQ_GHJ")
		)
		(pad "232" smd rect
			(at 4.59994 79.04988 90)
			(size 1.8034 0.508)
			(layers "F.Cu" "F.Mask" "F.Paste")
			(net "M_H_MA<13>")
		)
		(pad "233" smd rect
			(at 4.59994 79.900018 90)
			(size 1.8034 0.508)
			(layers "F.Cu" "F.Mask" "F.Paste")
			(net "PVDDQ_GHJ")
		)
		(pad "234" smd rect
			(at 4.59994 80.749902 90)
			(size 1.8034 0.508)
			(layers "F.Cu" "F.Mask" "F.Paste")
			(net "M_H_MA<17>")
		)
		(pad "235" smd rect
			(at 4.59994 81.60004 90)
			(size 1.8034 0.508)
			(layers "F.Cu" "F.Mask" "F.Paste")
			(net "M_H_C<2>")
		)
		(pad "236" smd rect
			(at 4.59994 82.449924 90)
			(size 1.8034 0.508)
			(layers "F.Cu" "F.Mask" "F.Paste")
			(net "PVDDQ_GHJ")
		)
		(pad "237" smd rect
			(at 4.59994 83.300062 90)
			(size 1.8034 0.508)
			(layers "F.Cu" "F.Mask" "F.Paste")
			(net "M_H_CS_N<3>")
		)
		(pad "238" smd rect
			(at 4.59994 84.149946 90)
			(size 1.8034 0.508)
			(layers "F.Cu" "F.Mask" "F.Paste")
			(net "GND")
		)
		(pad "239" smd rect
			(at 4.59994 85.000084 90)
			(size 1.8034 0.508)
			(layers "F.Cu" "F.Mask" "F.Paste")
			(net "GND")
		)
		(pad "240" smd rect
			(at 4.59994 85.849968 90)
			(size 1.8034 0.508)
			(layers "F.Cu" "F.Mask" "F.Paste")
			(net "M_H_DQ<36>")
		)
	)
)
